(kicad_pcb
	(version 20260206)
	(generator "pcbnew")
	(generator_version "10.0")
	(general
		(thickness 1.6)
		(legacy_teardrops no)
	)
	(paper "A4")
	(title_block
		(title "01162023_DA0F0TEBIF0_F0T_Expander_BD_F_brd_V02_OCP.brd")
		(comment 1 "Grand Teton / footprints 4364-4369 of 9728")
	)
	(layers
		(0 "F.Cu" signal "TOP")
		(4 "In1.Cu" signal "GND")
		(6 "In2.Cu" signal "VCC")
		(8 "In3.Cu" signal "VCC1")
		(10 "In4.Cu" signal "GND1")
		(12 "In5.Cu" signal "IN1")
		(14 "In6.Cu" signal "GND2")
		(16 "In7.Cu" signal "IN2")
		(18 "In8.Cu" signal "GND3")
		(20 "In9.Cu" signal "IN3")
		(22 "In10.Cu" signal "GND4")
		(24 "In11.Cu" signal "IN4")
		(26 "In12.Cu" signal "GND5")
		(28 "In13.Cu" signal "IN5")
		(30 "In14.Cu" signal "GND6")
		(32 "In15.Cu" signal "IN6")
		(34 "In16.Cu" signal "GND7")
		(2 "B.Cu" signal "BOTTOM")
		(9 "F.Adhes" user "F.Adhesive")
		(11 "B.Adhes" user "B.Adhesive")
		(13 "F.Paste" user "Package Geometry/Pastemask Top")
		(15 "B.Paste" user "Package Geometry/Pastemask Bottom")
		(5 "F.SilkS" user "Ref Des/Silkscreen Top")
		(7 "B.SilkS" user "Ref Des/Silkscreen Bottom")
		(1 "F.Mask" user "Board Geometry/Soldermask Top")
		(3 "B.Mask" user "Board Geometry/Soldermask Bottom")
		(17 "Dwgs.User" user "User.Drawings")
		(19 "Cmts.User" user "User.Comments")
		(21 "Eco1.User" user "User.Eco1")
		(23 "Eco2.User" user "User.Eco2")
		(25 "Edge.Cuts" user "Board Geometry/Outline")
		(27 "Margin" user)
		(31 "F.CrtYd" user "Package Geometry/Place Bound Top")
		(29 "B.CrtYd" user "Package Geometry/Place Bound Bottom")
		(35 "F.Fab" user "Ref Des/Assembly Top")
		(33 "B.Fab" user "Ref Des/Assembly Bottom")
	)
	(footprint ""
		(layer "F.Cu")
		(at 432.87569 -36.915598 -90)
		(property "Reference" "R5586"
			(at 0 0 270)
			(layer "F.SilkS")
			(hide yes)
			(effects
				(font
					(size 1.27 1.27)
				)
			)
		)
		(property "Value" ""
			(at 0 0 270)
			(layer "F.Fab")
			(effects
				(font
					(size 1.27 1.27)
				)
			)
		)
		(duplicate_pad_numbers_are_jumpers no)
		(fp_line
			(start -0.7874 0.4064)
			(end -0.7874 -0.4064)
			(stroke
				(width 0.1524)
				(type default)
			)
			(layer "F.SilkS")
		)
		(fp_line
			(start 0.7874 0.4064)
			(end -0.7874 0.4064)
			(stroke
				(width 0.1524)
				(type default)
			)
			(layer "F.SilkS")
		)
		(fp_line
			(start -0.7874 -0.4064)
			(end 0.7874 -0.4064)
			(stroke
				(width 0.1524)
				(type default)
			)
			(layer "F.SilkS")
		)
		(fp_line
			(start 0.7874 -0.4064)
			(end 0.7874 0.4064)
			(stroke
				(width 0.1524)
				(type default)
			)
			(layer "F.SilkS")
		)
		(fp_line
			(start -0.67945 0.3048)
			(end -0.67945 -0.305054)
			(stroke
				(width 0.1)
				(type default)
			)
			(layer "F.Fab")
		)
		(fp_line
			(start -0.12065 0.3048)
			(end -0.67945 0.3048)
			(stroke
				(width 0.1)
				(type default)
			)
			(layer "F.Fab")
		)
		(fp_line
			(start 0.120396 0.3048)
			(end 0.120396 0.2794)
			(stroke
				(width 0.1)
				(type default)
			)
			(layer "F.Fab")
		)
		(fp_line
			(start 0.67945 0.3048)
			(end 0.120396 0.3048)
			(stroke
				(width 0.1)
				(type default)
			)
			(layer "F.Fab")
		)
		(fp_line
			(start -0.12065 0.2794)
			(end -0.12065 0.3048)
			(stroke
				(width 0.1)
				(type default)
			)
			(layer "F.Fab")
		)
		(fp_line
			(start 0.120396 0.2794)
			(end -0.12065 0.2794)
			(stroke
				(width 0.1)
				(type default)
			)
			(layer "F.Fab")
		)
		(fp_line
			(start -0.12065 -0.2794)
			(end 0.12065 -0.2794)
			(stroke
				(width 0.1)
				(type default)
			)
			(layer "F.Fab")
		)
		(fp_line
			(start 0.12065 -0.2794)
			(end 0.12065 -0.3048)
			(stroke
				(width 0.1)
				(type default)
			)
			(layer "F.Fab")
		)
		(fp_line
			(start 0.12065 -0.3048)
			(end 0.67945 -0.3048)
			(stroke
				(width 0.1)
				(type default)
			)
			(layer "F.Fab")
		)
		(fp_line
			(start 0.67945 -0.3048)
			(end 0.67945 0.3048)
			(stroke
				(width 0.1)
				(type default)
			)
			(layer "F.Fab")
		)
		(fp_line
			(start -0.67945 -0.305054)
			(end -0.12065 -0.305054)
			(stroke
				(width 0.1)
				(type default)
			)
			(layer "F.Fab")
		)
		(fp_line
			(start -0.12065 -0.305054)
			(end -0.12065 -0.2794)
			(stroke
				(width 0.1)
				(type default)
			)
			(layer "F.Fab")
		)
		(pad "1" smd circle
			(at -0.40005 0 270)
			(size 0 0)
			(layers "F.Cu" "F.Mask" "F.Paste")
			(net "PRSNT_SSD15_R1_N")
		)
		(pad "2" smd circle
			(at 0.40005 0 270)
			(size 0 0)
			(layers "F.Cu" "F.Mask" "F.Paste")
			(net "PRSNT_SSD15_R_N")
		)
	)
	(footprint ""
		(layer "F.Cu")
		(at 38.608 -156.3624 180)
		(property "Reference" "R13"
			(at 0 0 180)
			(layer "F.SilkS")
			(hide yes)
			(effects
				(font
					(size 1.27 1.27)
				)
			)
		)
		(property "Value" ""
			(at 0 0 180)
			(layer "F.Fab")
			(effects
				(font
					(size 1.27 1.27)
				)
			)
		)
		(duplicate_pad_numbers_are_jumpers no)
		(fp_line
			(start 0.7874 0.4064)
			(end -0.7874 0.4064)
			(stroke
				(width 0.1524)
				(type default)
			)
			(layer "F.SilkS")
		)
		(fp_line
			(start 0.7874 -0.4064)
			(end 0.7874 0.4064)
			(stroke
				(width 0.1524)
				(type default)
			)
			(layer "F.SilkS")
		)
		(fp_line
			(start -0.7874 0.4064)
			(end -0.7874 -0.4064)
			(stroke
				(width 0.1524)
				(type default)
			)
			(layer "F.SilkS")
		)
		(fp_line
			(start -0.7874 -0.4064)
			(end 0.7874 -0.4064)
			(stroke
				(width 0.1524)
				(type default)
			)
			(layer "F.SilkS")
		)
		(fp_line
			(start 0.67945 0.3048)
			(end 0.120396 0.3048)
			(stroke
				(width 0.1)
				(type default)
			)
			(layer "F.Fab")
		)
		(fp_line
			(start 0.67945 -0.3048)
			(end 0.67945 0.3048)
			(stroke
				(width 0.1)
				(type default)
			)
			(layer "F.Fab")
		)
		(fp_line
			(start 0.12065 -0.2794)
			(end 0.12065 -0.3048)
			(stroke
				(width 0.1)
				(type default)
			)
			(layer "F.Fab")
		)
		(fp_line
			(start 0.12065 -0.3048)
			(end 0.67945 -0.3048)
			(stroke
				(width 0.1)
				(type default)
			)
			(layer "F.Fab")
		)
		(fp_line
			(start 0.120396 0.3048)
			(end 0.120396 0.2794)
			(stroke
				(width 0.1)
				(type default)
			)
			(layer "F.Fab")
		)
		(fp_line
			(start 0.120396 0.2794)
			(end -0.12065 0.2794)
			(stroke
				(width 0.1)
				(type default)
			)
			(layer "F.Fab")
		)
		(fp_line
			(start -0.12065 0.3048)
			(end -0.67945 0.3048)
			(stroke
				(width 0.1)
				(type default)
			)
			(layer "F.Fab")
		)
		(fp_line
			(start -0.12065 0.2794)
			(end -0.12065 0.3048)
			(stroke
				(width 0.1)
				(type default)
			)
			(layer "F.Fab")
		)
		(fp_line
			(start -0.12065 -0.2794)
			(end 0.12065 -0.2794)
			(stroke
				(width 0.1)
				(type default)
			)
			(layer "F.Fab")
		)
		(fp_line
			(start -0.12065 -0.305054)
			(end -0.12065 -0.2794)
			(stroke
				(width 0.1)
				(type default)
			)
			(layer "F.Fab")
		)
		(fp_line
			(start -0.67945 0.3048)
			(end -0.67945 -0.305054)
			(stroke
				(width 0.1)
				(type default)
			)
			(layer "F.Fab")
		)
		(fp_line
			(start -0.67945 -0.305054)
			(end -0.12065 -0.305054)
			(stroke
				(width 0.1)
				(type default)
			)
			(layer "F.Fab")
		)
		(pad "1" smd circle
			(at -0.40005 0 180)
			(size 0 0)
			(layers "F.Cu" "F.Mask" "F.Paste")
			(net "NIC0_DATA_OUT")
		)
		(pad "2" smd circle
			(at 0.40005 0 180)
			(size 0 0)
			(layers "F.Cu" "F.Mask" "F.Paste")
			(net "GND")
		)
	)
	(footprint ""
		(layer "F.Cu")
		(at 346.782136 -37.025072)
		(property "Reference" "R5701"
			(at 0 0 0)
			(layer "F.SilkS")
			(hide yes)
			(effects
				(font
					(size 1.27 1.27)
				)
			)
		)
		(property "Value" ""
			(at 0 0 0)
			(layer "F.Fab")
			(effects
				(font
					(size 1.27 1.27)
				)
			)
		)
		(duplicate_pad_numbers_are_jumpers no)
		(fp_line
			(start -0.7874 -0.4064)
			(end 0.7874 -0.4064)
			(stroke
				(width 0.1524)
				(type default)
			)
			(layer "F.SilkS")
		)
		(fp_line
			(start -0.7874 0.4064)
			(end -0.7874 -0.4064)
			(stroke
				(width 0.1524)
				(type default)
			)
			(layer "F.SilkS")
		)
		(fp_line
			(start 0.7874 -0.4064)
			(end 0.7874 0.4064)
			(stroke
				(width 0.1524)
				(type default)
			)
			(layer "F.SilkS")
		)
		(fp_line
			(start 0.7874 0.4064)
			(end -0.7874 0.4064)
			(stroke
				(width 0.1524)
				(type default)
			)
			(layer "F.SilkS")
		)
		(fp_line
			(start -0.67945 -0.305054)
			(end -0.12065 -0.305054)
			(stroke
				(width 0.1)
				(type default)
			)
			(layer "F.Fab")
		)
		(fp_line
			(start -0.67945 0.3048)
			(end -0.67945 -0.305054)
			(stroke
				(width 0.1)
				(type default)
			)
			(layer "F.Fab")
		)
		(fp_line
			(start -0.12065 -0.305054)
			(end -0.12065 -0.2794)
			(stroke
				(width 0.1)
				(type default)
			)
			(layer "F.Fab")
		)
		(fp_line
			(start -0.12065 -0.2794)
			(end 0.12065 -0.2794)
			(stroke
				(width 0.1)
				(type default)
			)
			(layer "F.Fab")
		)
		(fp_line
			(start -0.12065 0.2794)
			(end -0.12065 0.3048)
			(stroke
				(width 0.1)
				(type default)
			)
			(layer "F.Fab")
		)
		(fp_line
			(start -0.12065 0.3048)
			(end -0.67945 0.3048)
			(stroke
				(width 0.1)
				(type default)
			)
			(layer "F.Fab")
		)
		(fp_line
			(start 0.120396 0.2794)
			(end -0.12065 0.2794)
			(stroke
				(width 0.1)
				(type default)
			)
			(layer "F.Fab")
		)
		(fp_line
			(start 0.120396 0.3048)
			(end 0.120396 0.2794)
			(stroke
				(width 0.1)
				(type default)
			)
			(layer "F.Fab")
		)
		(fp_line
			(start 0.12065 -0.3048)
			(end 0.67945 -0.3048)
			(stroke
				(width 0.1)
				(type default)
			)
			(layer "F.Fab")
		)
		(fp_line
			(start 0.12065 -0.2794)
			(end 0.12065 -0.3048)
			(stroke
				(width 0.1)
				(type default)
			)
			(layer "F.Fab")
		)
		(fp_line
			(start 0.67945 -0.3048)
			(end 0.67945 0.3048)
			(stroke
				(width 0.1)
				(type default)
			)
			(layer "F.Fab")
		)
		(fp_line
			(start 0.67945 0.3048)
			(end 0.120396 0.3048)
			(stroke
				(width 0.1)
				(type default)
			)
			(layer "F.Fab")
		)
		(pad "1" smd circle
			(at -0.40005 0)
			(size 0 0)
			(layers "F.Cu" "F.Mask" "F.Paste")
			(net "RST_SMB_SSD_R_N")
		)
		(pad "2" smd circle
			(at 0.40005 0)
			(size 0 0)
			(layers "F.Cu" "F.Mask" "F.Paste")
			(net "RST_SMB_SSD12_N")
		)
	)
	(footprint ""
		(layer "F.Cu")
		(at 6.467348 -251.312426 -90)
		(property "Reference" "C4243"
			(at 0 0 270)
			(layer "F.SilkS")
			(hide yes)
			(effects
				(font
					(size 1.27 1.27)
				)
			)
		)
		(property "Value" ""
			(at 0 0 270)
			(layer "F.Fab")
			(effects
				(font
					(size 1.27 1.27)
				)
			)
		)
		(duplicate_pad_numbers_are_jumpers no)
		(fp_line
			(start -1.2954 0.5842)
			(end -1.2954 -0.5842)
			(stroke
				(width 0.1524)
				(type default)
			)
			(layer "F.SilkS")
		)
		(fp_line
			(start 1.2954 0.5842)
			(end -1.2954 0.5842)
			(stroke
				(width 0.1524)
				(type default)
			)
			(layer "F.SilkS")
		)
		(fp_line
			(start -1.2954 -0.5842)
			(end 1.2954 -0.5842)
			(stroke
				(width 0.1524)
				(type default)
			)
			(layer "F.SilkS")
		)
		(fp_line
			(start 1.2954 -0.5842)
			(end 1.2954 0.5842)
			(stroke
				(width 0.1524)
				(type default)
			)
			(layer "F.SilkS")
		)
		(fp_line
			(start -0.8636 0.4572)
			(end -0.8636 0.4064)
			(stroke
				(width 0.1)
				(type default)
			)
			(layer "F.Fab")
		)
		(fp_line
			(start 0.8636 0.4572)
			(end -0.8636 0.4572)
			(stroke
				(width 0.1)
				(type default)
			)
			(layer "F.Fab")
		)
		(fp_line
			(start -1.1938 0.4064)
			(end -1.1938 -0.4064)
			(stroke
				(width 0.1)
				(type default)
			)
			(layer "F.Fab")
		)
		(fp_line
			(start -0.8636 0.4064)
			(end -1.1938 0.4064)
			(stroke
				(width 0.1)
				(type default)
			)
			(layer "F.Fab")
		)
		(fp_line
			(start 0.8636 0.4064)
			(end 0.8636 0.4572)
			(stroke
				(width 0.1)
				(type default)
			)
			(layer "F.Fab")
		)
		(fp_line
			(start 1.1938 0.4064)
			(end 0.8636 0.4064)
			(stroke
				(width 0.1)
				(type default)
			)
			(layer "F.Fab")
		)
		(fp_line
			(start -1.1938 -0.4064)
			(end -0.8636 -0.4064)
			(stroke
				(width 0.1)
				(type default)
			)
			(layer "F.Fab")
		)
		(fp_line
			(start -0.8636 -0.4064)
			(end -0.8636 -0.4572)
			(stroke
				(width 0.1)
				(type default)
			)
			(layer "F.Fab")
		)
		(fp_line
			(start 0.8636 -0.4064)
			(end 1.1938 -0.4064)
			(stroke
				(width 0.1)
				(type default)
			)
			(layer "F.Fab")
		)
		(fp_line
			(start 1.1938 -0.4064)
			(end 1.1938 0.4064)
			(stroke
				(width 0.1)
				(type default)
			)
			(layer "F.Fab")
		)
		(fp_line
			(start -0.8636 -0.4572)
			(end 0.8636 -0.4572)
			(stroke
				(width 0.1)
				(type default)
			)
			(layer "F.Fab")
		)
		(fp_line
			(start 0.8636 -0.4572)
			(end 0.8636 -0.4064)
			(stroke
				(width 0.1)
				(type default)
			)
			(layer "F.Fab")
		)
		(pad "1" smd rect
			(at -0.7366 0 180)
			(size 0.7112 0.8128)
			(layers "F.Cu" "F.Mask" "F.Paste")
			(net "P1V25_SERDES_VDDPLL_PEX0_C9")
		)
		(pad "2" smd rect
			(at 0.7366 0 180)
			(size 0.7112 0.8128)
			(layers "F.Cu" "F.Mask" "F.Paste")
			(net "GND")
		)
	)
	(footprint ""
		(layer "F.Cu")
		(at 366.092486 -28.225242 180)
		(property "Reference" "C705"
			(at 0 0 180)
			(layer "F.SilkS")
			(hide yes)
			(effects
				(font
					(size 1.27 1.27)
				)
			)
		)
		(property "Value" ""
			(at 0 0 180)
			(layer "F.Fab")
			(effects
				(font
					(size 1.27 1.27)
				)
			)
		)
		(duplicate_pad_numbers_are_jumpers no)
		(fp_line
			(start 0.299974 0.150114)
			(end -0.299974 0.150114)
			(stroke
				(width 0.1)
				(type default)
			)
			(layer "F.Fab")
		)
		(fp_line
			(start 0.299974 -0.150114)
			(end 0.299974 0.150114)
			(stroke
				(width 0.1)
				(type default)
			)
			(layer "F.Fab")
		)
		(fp_line
			(start -0.299974 0.150114)
			(end -0.299974 -0.150114)
			(stroke
				(width 0.1)
				(type default)
			)
			(layer "F.Fab")
		)
		(fp_line
			(start -0.299974 -0.150114)
			(end 0.299974 -0.150114)
			(stroke
				(width 0.1)
				(type default)
			)
			(layer "F.Fab")
		)
		(pad "1" smd rect
			(at -0.2667 0 180)
			(size 0.3048 0.381)
			(layers "F.Cu" "F.Mask" "F.Paste")
			(net "P5E_PEX3_STN2_TX_DN<44>")
		)
		(pad "2" smd rect
			(at 0.2667 0 180)
			(size 0.3048 0.381)
			(layers "F.Cu" "F.Mask" "F.Paste")
			(net "P5E_PEX3_STN2_TX_C_DN<44>")
		)
	)
	(footprint ""
		(layer "F.Cu")
		(at 435.306724 -294.77335 90)
		(property "Reference" "U428"
			(at -1.0922 -2.174748 90)
			(unlocked yes)
			(layer "F.SilkS")
			(effects
				(font
					(size 0.7874 0.5842)
					(thickness 0.1524)
				)
				(justify left)
			)
		)
		(property "Value" ""
			(at 0 0 90)
			(layer "F.Fab")
			(effects
				(font
					(size 1.27 1.27)
				)
			)
		)
		(duplicate_pad_numbers_are_jumpers no)
		(fp_line
			(start 1.0414 -1.575054)
			(end 1.0414 1.575054)
			(stroke
				(width 0.1524)
				(type default)
			)
			(layer "F.SilkS")
		)
		(fp_line
			(start 0.254 -1.575054)
			(end 1.0414 -1.575054)
			(stroke
				(width 0.1524)
				(type default)
			)
			(layer "F.SilkS")
		)
		(fp_line
			(start 0.2286 -1.575054)
			(end 0 -1.272032)
			(stroke
				(width 0.1524)
				(type default)
			)
			(layer "F.SilkS")
		)
		(fp_line
			(start -1.0414 -1.575054)
			(end -0.254 -1.575054)
			(stroke
				(width 0.1524)
				(type default)
			)
			(layer "F.SilkS")
		)
		(fp_line
			(start 0 -1.272032)
			(end -0.254 -1.575054)
			(stroke
				(width 0.1524)
				(type default)
			)
			(layer "F.SilkS")
		)
		(fp_line
			(start 1.0414 1.575054)
			(end -1.0414 1.575054)
			(stroke
				(width 0.1524)
				(type default)
			)
			(layer "F.SilkS")
		)
		(fp_line
			(start -1.0414 1.575054)
			(end -1.0414 -1.575054)
			(stroke
				(width 0.1524)
				(type default)
			)
			(layer "F.SilkS")
		)
		(fp_poly
			(pts
				(xy -2.710688 -0.975106) (xy -3.726688 -1.483106) (xy -3.726688 -0.467106)
			)
			(stroke
				(width 0)
				(type default)
			)
			(fill yes)
			(layer "F.SilkS")
		)
		(fp_line
			(start 1.4478 -1.5748)
			(end 1.4478 -1.2192)
			(stroke
				(width 0.1)
				(type default)
			)
			(layer "F.Fab")
		)
		(fp_line
			(start -1.4478 -1.5748)
			(end 1.4478 -1.5748)
			(stroke
				(width 0.1)
				(type default)
			)
			(layer "F.Fab")
		)
		(fp_line
			(start 2.5654 -1.2192)
			(end 2.5654 1.2192)
			(stroke
				(width 0.1)
				(type default)
			)
			(layer "F.Fab")
		)
		(fp_line
			(start 1.4478 -1.2192)
			(end 2.5654 -1.2192)
			(stroke
				(width 0.1)
				(type default)
			)
			(layer "F.Fab")
		)
		(fp_line
			(start -1.4478 -1.2192)
			(end -1.4478 -1.5748)
			(stroke
				(width 0.1)
				(type default)
			)
			(layer "F.Fab")
		)
		(fp_line
			(start -2.5654 -1.2192)
			(end -1.4478 -1.2192)
			(stroke
				(width 0.1)
				(type default)
			)
			(layer "F.Fab")
		)
		(fp_line
			(start 2.5654 1.2192)
			(end 1.4478 1.2192)
			(stroke
				(width 0.1)
				(type default)
			)
			(layer "F.Fab")
		)
		(fp_line
			(start 1.4478 1.2192)
			(end 1.4478 1.5748)
			(stroke
				(width 0.1)
				(type default)
			)
			(layer "F.Fab")
		)
		(fp_line
			(start -1.4478 1.2192)
			(end -2.5654 1.2192)
			(stroke
				(width 0.1)
				(type default)
			)
			(layer "F.Fab")
		)
		(fp_line
			(start -2.5654 1.2192)
			(end -2.5654 -1.2192)
			(stroke
				(width 0.1)
				(type default)
			)
			(layer "F.Fab")
		)
		(fp_line
			(start 1.4478 1.5748)
			(end -1.4478 1.5748)
			(stroke
				(width 0.1)
				(type default)
			)
			(layer "F.Fab")
		)
		(fp_line
			(start -1.4478 1.5748)
			(end -1.4478 1.2192)
			(stroke
				(width 0.1)
				(type default)
			)
			(layer "F.Fab")
		)
		(fp_poly
			(pts
				(xy -2.710688 -0.975106) (xy -3.726688 -1.483106) (xy -3.726688 -0.467106)
			)
			(stroke
				(width 0)
				(type default)
			)
			(fill yes)
			(layer "F.Fab")
		)
		(pad "1" smd rect
			(at -1.849882 -0.975106)
			(size 0.3556 1.3208)
			(layers "F.Cu" "F.Mask" "F.Paste")
			(net "RST_PEX3_PERST_R_N")
		)
		(pad "2" smd rect
			(at -1.849882 -0.32512)
			(size 0.3556 1.3208)
			(layers "F.Cu" "F.Mask" "F.Paste")
			(net "RST_PEX3_S0_PERST_N")
		)
		(pad "3" smd rect
			(at -1.849882 0.32512)
			(size 0.3556 1.3208)
			(layers "F.Cu" "F.Mask" "F.Paste")
			(net "RST_PEX3_PERST_R_N")
		)
		(pad "4" smd rect
			(at -1.849882 0.975106)
			(size 0.3556 1.3208)
			(layers "F.Cu" "F.Mask" "F.Paste")
			(net "GND")
		)
		(pad "5" smd rect
			(at 1.849882 0.975106)
			(size 0.3556 1.3208)
			(layers "F.Cu" "F.Mask" "F.Paste")
			(net "RST_PEX3_S1_PERST_N")
		)
		(pad "6" smd rect
			(at 1.849882 0.32512)
			(size 0.3556 1.3208)
			(layers "F.Cu" "F.Mask" "F.Paste")
			(net "RST_PEX3_PERST_R_N")
		)
		(pad "7" smd rect
			(at 1.849882 -0.32512)
			(size 0.3556 1.3208)
			(layers "F.Cu" "F.Mask" "F.Paste")
			(net "RST_PEX3_S3_PERST_N")
		)
		(pad "8" smd rect
			(at 1.849882 -0.975106)
			(size 0.3556 1.3208)
			(layers "F.Cu" "F.Mask" "F.Paste")
			(net "P1V8_PEX")
		)
	)
)
